(kicad_pcb
	(version 20241229)
	(generator "pcbnew")
	(generator_version "9.0")
	(general
		(thickness 1.6296)
		(legacy_teardrops no)
	)
	(paper "A3")
	(title_block
		(title "Thunderbolt to 10GbE adapter")
		(date "2026-04-21")
		(rev "1.1.0")
		(company "Antmicro Ltd")
		(comment 1 "www.antmicro.com")
		(comment 9 "footprints 383-387 of 703")
	)
	(layers
		(0 "F.Cu" signal)
		(4 "In1.Cu" signal)
		(6 "In2.Cu" signal)
		(8 "In3.Cu" signal)
		(10 "In4.Cu" signal)
		(12 "In5.Cu" signal)
		(14 "In6.Cu" signal)
		(2 "B.Cu" signal)
		(9 "F.Adhes" user "F.Adhesive")
		(11 "B.Adhes" user "B.Adhesive")
		(13 "F.Paste" user)
		(15 "B.Paste" user)
		(5 "F.SilkS" user "F.Silkscreen")
		(7 "B.SilkS" user "B.Silkscreen")
		(1 "F.Mask" user)
		(3 "B.Mask" user)
		(17 "Dwgs.User" user "User.Drawings")
		(19 "Cmts.User" user "User.Comments")
		(21 "Eco1.User" user "User.Eco1")
		(23 "Eco2.User" user "User.Eco2")
		(25 "Edge.Cuts" user)
		(27 "Margin" user)
		(31 "F.CrtYd" user "F.Courtyard")
		(29 "B.CrtYd" user "B.Courtyard")
		(35 "F.Fab" user)
		(33 "B.Fab" user)
	)
	(footprint "antmicro-footprints:R_0402_1005Metric"
		(layer "B.Cu")
		(at 135 93.4 90)
		(descr "Resistor SMD 0402")
		(tags "resistor SMD 0402")
		(property "Reference" "R87"
			(at -1 0.4 270)
			(layer "B.SilkS")
			(effects
				(font
					(size 0.7 0.7)
					(thickness 0.15)
				)
				(justify left bottom mirror)
			)
		)
		(property "Value" "R_100k_0402"
			(at -1.011843 -1.772047 270)
			(layer "B.Fab")
			(effects
				(font
					(size 0.7 0.7)
					(thickness 0.15)
				)
				(justify left bottom mirror)
			)
		)
		(property "Datasheet" "https://www.bourns.com/docs/product-datasheets/cr.pdf"
			(at 0 0 270)
			(layer "B.Fab")
			(hide yes)
			(effects
				(font
					(size 1.27 1.27)
					(thickness 0.15)
				)
				(justify mirror)
			)
		)
		(property "Description" "SMD Chip Resistor, 100 kohm, ± 1%, 62.5 mW, 0402 [1005 Metric], Thick Film, General Purpose"
			(at 0 0 270)
			(layer "B.Fab")
			(hide yes)
			(effects
				(font
					(size 1.27 1.27)
					(thickness 0.15)
				)
				(justify mirror)
			)
		)
		(property "MPN" "CR0402-FX-1003GLF"
			(at 0 0 90)
			(unlocked yes)
			(layer "B.Fab")
			(hide yes)
			(effects
				(font
					(size 1 1)
					(thickness 0.15)
				)
				(justify mirror)
			)
		)
		(property "Manufacturer" "Bourns"
			(at 0 0 90)
			(unlocked yes)
			(layer "B.Fab")
			(hide yes)
			(effects
				(font
					(size 1 1)
					(thickness 0.15)
				)
				(justify mirror)
			)
		)
		(property "License" "Apache-2.0"
			(at 0 0 90)
			(unlocked yes)
			(layer "B.Fab")
			(hide yes)
			(effects
				(font
					(size 1 1)
					(thickness 0.15)
				)
				(justify mirror)
			)
		)
		(property "Author" "Antmicro"
			(at 0 0 90)
			(unlocked yes)
			(layer "B.Fab")
			(hide yes)
			(effects
				(font
					(size 1 1)
					(thickness 0.15)
				)
				(justify mirror)
			)
		)
		(property "Val" "100k"
			(at 0 0 90)
			(unlocked yes)
			(layer "B.Fab")
			(hide yes)
			(effects
				(font
					(size 1 1)
					(thickness 0.15)
				)
				(justify mirror)
			)
		)
		(property "Tolerance" "1%"
			(at 0 0 90)
			(unlocked yes)
			(layer "B.Fab")
			(hide yes)
			(effects
				(font
					(size 1 1)
					(thickness 0.15)
				)
				(justify mirror)
			)
		)
		(sheetname "/X710 DCDC converters/")
		(sheetfile "DCDC_converters_X710.kicad_sch")
		(attr smd)
		(fp_rect
			(start -0.925 0.47)
			(end 0.925 -0.47)
			(stroke
				(width 0.05)
				(type default)
			)
			(fill no)
			(layer "B.CrtYd")
		)
		(fp_rect
			(start -0.5 0.25)
			(end 0.5 -0.25)
			(stroke
				(width 0.15)
				(type solid)
			)
			(fill no)
			(layer "B.Fab")
		)
		(fp_text user "Author: Antmicro"
			(at -0.95 -4.169 270)
			(layer "B.Fab")
			(effects
				(font
					(size 0.7 0.7)
					(thickness 0.15)
				)
				(justify left bottom mirror)
			)
		)
		(fp_text user "${REFERENCE}"
			(at -0.95 -3.168 270)
			(layer "B.Fab")
			(effects
				(font
					(size 0.7 0.7)
					(thickness 0.15)
				)
				(justify left bottom mirror)
			)
		)
		(fp_text user "License: Apache-2.0"
			(at -0.95 -5.169 270)
			(layer "B.Fab")
			(effects
				(font
					(size 0.7 0.7)
					(thickness 0.15)
				)
				(justify left bottom mirror)
			)
		)
		(pad "1" smd roundrect
			(at -0.48 0 90)
			(size 0.59 0.64)
			(layers "B.Cu" "B.Mask" "B.Paste")
			(roundrect_rratio 0.25)
			(net 378 "/X710 DCDC converters/3V3_PG")
			(pintype "passive")
		)
		(pad "2" smd roundrect
			(at 0.48 0 90)
			(size 0.59 0.64)
			(layers "B.Cu" "B.Mask" "B.Paste")
			(roundrect_rratio 0.25)
			(net 80 "/X710 DCDC converters/3V3_VCC")
			(pintype "passive")
		)
	)
	(footprint "antmicro-footprints:C_0402_1005Metric"
		(layer "B.Cu")
		(at 153.031866 76.260117 180)
		(descr "Capacitor SMD 0402")
		(tags "capacitor SMD 0402")
		(property "Reference" "C217"
			(at -21.168135 -9.464883 0)
			(layer "B.SilkS")
			(effects
				(font
					(size 0.7 0.7)
					(thickness 0.15)
				)
				(justify mirror)
			)
		)
		(property "Value" "C_1u_25V_0402"
			(at -1.022927 -2.155213 0)
			(layer "B.Fab")
			(effects
				(font
					(size 0.7 0.7)
					(thickness 0.15)
				)
				(justify left bottom mirror)
			)
		)
		(property "Datasheet" "https://www.murata.com/products/productdetail?partno=GRM155R61E105KE11%23"
			(at 0 0 0)
			(layer "B.Fab")
			(hide yes)
			(effects
				(font
					(size 1.27 1.27)
					(thickness 0.15)
				)
				(justify mirror)
			)
		)
		(property "Description" "SMD Multilayer Ceramic Capacitor, 1 µF, 25 V, 0402 [1005 Metric], ± 10%, X5R, GRM Series"
			(at 0 0 0)
			(layer "B.Fab")
			(hide yes)
			(effects
				(font
					(size 1.27 1.27)
					(thickness 0.15)
				)
				(justify mirror)
			)
		)
		(property "MPN" "GRM155R61E105KE11J"
			(at 0 0 180)
			(unlocked yes)
			(layer "B.Fab")
			(hide yes)
			(effects
				(font
					(size 1 1)
					(thickness 0.15)
				)
				(justify mirror)
			)
		)
		(property "Manufacturer" "Murata"
			(at 0 0 180)
			(unlocked yes)
			(layer "B.Fab")
			(hide yes)
			(effects
				(font
					(size 1 1)
					(thickness 0.15)
				)
				(justify mirror)
			)
		)
		(property "License" "Apache-2.0"
			(at 0 0 180)
			(unlocked yes)
			(layer "B.Fab")
			(hide yes)
			(effects
				(font
					(size 1 1)
					(thickness 0.15)
				)
				(justify mirror)
			)
		)
		(property "Author" "Antmicro"
			(at 0 0 180)
			(unlocked yes)
			(layer "B.Fab")
			(hide yes)
			(effects
				(font
					(size 1 1)
					(thickness 0.15)
				)
				(justify mirror)
			)
		)
		(property "Val" "1u"
			(at 0 0 180)
			(unlocked yes)
			(layer "B.Fab")
			(hide yes)
			(effects
				(font
					(size 1 1)
					(thickness 0.15)
				)
				(justify mirror)
			)
		)
		(property "Voltage" "25V"
			(at 0 0 180)
			(unlocked yes)
			(layer "B.Fab")
			(hide yes)
			(effects
				(font
					(size 1 1)
					(thickness 0.15)
				)
				(justify mirror)
			)
		)
		(property "Dielectric" "X5R"
			(at 0 0 180)
			(unlocked yes)
			(layer "B.Fab")
			(hide yes)
			(effects
				(font
					(size 1 1)
					(thickness 0.15)
				)
				(justify mirror)
			)
		)
		(sheetname "/X710-AT2 power/")
		(sheetfile "x710-at2-power.kicad_sch")
		(attr smd)
		(fp_rect
			(start -0.925 0.47)
			(end 0.925 -0.47)
			(stroke
				(width 0.05)
				(type default)
			)
			(fill no)
			(layer "B.CrtYd")
		)
		(fp_line
			(start 0.504 0.25)
			(end 0.504 -0.248)
			(stroke
				(width 0.15)
				(type solid)
			)
			(layer "B.Fab")
		)
		(fp_line
			(start 0.504 -0.248)
			(end -0.494 -0.248)
			(stroke
				(width 0.15)
				(type solid)
			)
			(layer "B.Fab")
		)
		(fp_line
			(start -0.494 0.25)
			(end 0.504 0.25)
			(stroke
				(width 0.15)
				(type solid)
			)
			(layer "B.Fab")
		)
		(fp_line
			(start -0.494 -0.248)
			(end -0.494 0.25)
			(stroke
				(width 0.15)
				(type solid)
			)
			(layer "B.Fab")
		)
		(fp_text user "License: Apache-2.0"
			(at -0.939 -5.799 0)
			(layer "B.Fab")
			(effects
				(font
					(size 0.7 0.7)
					(thickness 0.15)
				)
				(justify left bottom mirror)
			)
		)
		(fp_text user "${REFERENCE}"
			(at -0.939 -4.599 0)
			(layer "B.Fab")
			(effects
				(font
					(size 0.7 0.7)
					(thickness 0.15)
				)
				(justify left bottom mirror)
			)
		)
		(fp_text user "Author: Antmicro"
			(at -0.939 -3.399 0)
			(layer "B.Fab")
			(effects
				(font
					(size 0.7 0.7)
					(thickness 0.15)
				)
				(justify left bottom mirror)
			)
		)
		(pad "1" smd roundrect
			(at -0.48 0 180)
			(size 0.59 0.64)
			(layers "B.Cu" "B.Mask" "B.Paste")
			(roundrect_rratio 0.25)
			(net 23 "GND")
			(pintype "passive")
		)
		(pad "2" smd roundrect
			(at 0.48 0 180)
			(size 0.59 0.64)
			(layers "B.Cu" "B.Mask" "B.Paste")
			(roundrect_rratio 0.25)
			(net 1 "VCCA")
			(pintype "passive")
		)
	)
	(footprint "antmicro-footprints:C_0402_1005Metric"
		(layer "B.Cu")
		(at 127.25 134.75 90)
		(descr "Capacitor SMD 0402")
		(tags "capacitor SMD 0402")
		(property "Reference" "C34"
			(at -1.25 0.5 270)
			(layer "B.SilkS")
			(effects
				(font
					(size 0.7 0.7)
					(thickness 0.15)
				)
				(justify left bottom mirror)
			)
		)
		(property "Value" "C_220n_0402"
			(at -1.022927 -2.155213 270)
			(layer "B.Fab")
			(effects
				(font
					(size 0.7 0.7)
					(thickness 0.15)
				)
				(justify left bottom mirror)
			)
		)
		(property "Datasheet" "https://www.yageo.com/en/Chart/Download/pdf/CC0402KRX5R6BB224"
			(at 0 0 270)
			(layer "B.Fab")
			(hide yes)
			(effects
				(font
					(size 1.27 1.27)
					(thickness 0.15)
				)
				(justify mirror)
			)
		)
		(property "Description" "SMD Multilayer Ceramic Capacitor, 0.22 µF, 10 V, 0402 [1005 Metric], ± 10%, X5R, CC Series"
			(at 0 0 270)
			(layer "B.Fab")
			(hide yes)
			(effects
				(font
					(size 1.27 1.27)
					(thickness 0.15)
				)
				(justify mirror)
			)
		)
		(property "MPN" "CC0402KRX5R6BB224"
			(at 0 0 90)
			(unlocked yes)
			(layer "B.Fab")
			(hide yes)
			(effects
				(font
					(size 1 1)
					(thickness 0.15)
				)
				(justify mirror)
			)
		)
		(property "Manufacturer" "YAGEO"
			(at 0 0 90)
			(unlocked yes)
			(layer "B.Fab")
			(hide yes)
			(effects
				(font
					(size 1 1)
					(thickness 0.15)
				)
				(justify mirror)
			)
		)
		(property "License" "Apache-2.0"
			(at 0 0 90)
			(unlocked yes)
			(layer "B.Fab")
			(hide yes)
			(effects
				(font
					(size 1 1)
					(thickness 0.15)
				)
				(justify mirror)
			)
		)
		(property "Val" "220n"
			(at 0 0 90)
			(unlocked yes)
			(layer "B.Fab")
			(hide yes)
			(effects
				(font
					(size 1 1)
					(thickness 0.15)
				)
				(justify mirror)
			)
		)
		(property "Voltage" ""
			(at 0 0 90)
			(unlocked yes)
			(layer "B.Fab")
			(hide yes)
			(effects
				(font
					(size 1 1)
					(thickness 0.15)
				)
				(justify mirror)
			)
		)
		(property "Dielectric" ""
			(at 0 0 90)
			(unlocked yes)
			(layer "B.Fab")
			(hide yes)
			(effects
				(font
					(size 1 1)
					(thickness 0.15)
				)
				(justify mirror)
			)
		)
		(property "Author" "Antmicro"
			(at 0 0 90)
			(unlocked yes)
			(layer "B.Fab")
			(hide yes)
			(effects
				(font
					(size 1 1)
					(thickness 0.15)
				)
				(justify mirror)
			)
		)
		(sheetname "/TB Controller/")
		(sheetfile "tb.kicad_sch")
		(attr smd)
		(fp_rect
			(start -0.925 0.47)
			(end 0.925 -0.47)
			(stroke
				(width 0.05)
				(type default)
			)
			(fill no)
			(layer "B.CrtYd")
		)
		(fp_line
			(start 0.504 -0.248)
			(end -0.494 -0.248)
			(stroke
				(width 0.15)
				(type solid)
			)
			(layer "B.Fab")
		)
		(fp_line
			(start -0.494 -0.248)
			(end -0.494 0.25)
			(stroke
				(width 0.15)
				(type solid)
			)
			(layer "B.Fab")
		)
		(fp_line
			(start 0.504 0.25)
			(end 0.504 -0.248)
			(stroke
				(width 0.15)
				(type solid)
			)
			(layer "B.Fab")
		)
		(fp_line
			(start -0.494 0.25)
			(end 0.504 0.25)
			(stroke
				(width 0.15)
				(type solid)
			)
			(layer "B.Fab")
		)
		(fp_text user "${REFERENCE}"
			(at -0.939 -4.599 270)
			(layer "B.Fab")
			(effects
				(font
					(size 0.7 0.7)
					(thickness 0.15)
				)
				(justify left bottom mirror)
			)
		)
		(fp_text user "License: Apache-2.0"
			(at -0.939 -5.799 270)
			(layer "B.Fab")
			(effects
				(font
					(size 0.7 0.7)
					(thickness 0.15)
				)
				(justify left bottom mirror)
			)
		)
		(fp_text user "Author: Antmicro"
			(at -0.939 -3.399 270)
			(layer "B.Fab")
			(effects
				(font
					(size 0.7 0.7)
					(thickness 0.15)
				)
				(justify left bottom mirror)
			)
		)
		(pad "1" smd roundrect
			(at -0.48 0 90)
			(size 0.59 0.64)
			(layers "B.Cu" "B.Mask" "B.Paste")
			(roundrect_rratio 0.25)
			(net 309 "/PD and TB DC-DC/USB3.TX1_P")
			(pintype "passive")
		)
		(pad "2" smd roundrect
			(at 0.48 0 90)
			(size 0.59 0.64)
			(layers "B.Cu" "B.Mask" "B.Paste")
			(roundrect_rratio 0.25)
			(net 168 "/TB Controller/PA_TX1_P")
			(pintype "passive")
		)
	)
	(footprint "antmicro-footprints:R_0402_1005Metric"
		(layer "B.Cu")
		(at 142.5 115.099997 180)
		(descr "Resistor SMD 0402")
		(tags "resistor SMD 0402")
		(property "Reference" "R65"
			(at -19.75 7.450001 0)
			(layer "B.SilkS")
			(effects
				(font
					(size 0.7 0.7)
					(thickness 0.15)
				)
				(justify mirror)
			)
		)
		(property "Value" "R_10k_0402"
			(at -1.011843 -1.772047 0)
			(layer "B.Fab")
			(effects
				(font
					(size 0.7 0.7)
					(thickness 0.15)
				)
				(justify left bottom mirror)
			)
		)
		(property "Datasheet" "https://www.bourns.com/docs/product-datasheets/cr.pdf"
			(at 0 0 0)
			(layer "B.Fab")
			(hide yes)
			(effects
				(font
					(size 1.27 1.27)
					(thickness 0.15)
				)
				(justify mirror)
			)
		)
		(property "Description" "SMD Chip Resistor, 10 kohm, ± 1%, 62.5 mW, 0402 [1005 Metric], Thick Film, General Purpose"
			(at 0 0 0)
			(layer "B.Fab")
			(hide yes)
			(effects
				(font
					(size 1.27 1.27)
					(thickness 0.15)
				)
				(justify mirror)
			)
		)
		(property "MPN" "CR0402-FX-1002GLF"
			(at 0 0 180)
			(unlocked yes)
			(layer "B.Fab")
			(hide yes)
			(effects
				(font
					(size 1 1)
					(thickness 0.15)
				)
				(justify mirror)
			)
		)
		(property "Manufacturer" "Bourns"
			(at 0 0 180)
			(unlocked yes)
			(layer "B.Fab")
			(hide yes)
			(effects
				(font
					(size 1 1)
					(thickness 0.15)
				)
				(justify mirror)
			)
		)
		(property "License" "Apache-2.0"
			(at 0 0 180)
			(unlocked yes)
			(layer "B.Fab")
			(hide yes)
			(effects
				(font
					(size 1 1)
					(thickness 0.15)
				)
				(justify mirror)
			)
		)
		(property "Val" "10k"
			(at 0 0 180)
			(unlocked yes)
			(layer "B.Fab")
			(hide yes)
			(effects
				(font
					(size 1 1)
					(thickness 0.15)
				)
				(justify mirror)
			)
		)
		(property "Tolerance" "1%"
			(at 0 0 180)
			(unlocked yes)
			(layer "B.Fab")
			(hide yes)
			(effects
				(font
					(size 1 1)
					(thickness 0.15)
				)
				(justify mirror)
			)
		)
		(property "Author" "Antmicro"
			(at 0 0 180)
			(unlocked yes)
			(layer "B.Fab")
			(hide yes)
			(effects
				(font
					(size 1 1)
					(thickness 0.15)
				)
				(justify mirror)
			)
		)
		(sheetname "/TB Controller/")
		(sheetfile "tb.kicad_sch")
		(attr smd)
		(fp_rect
			(start -0.925 0.47)
			(end 0.925 -0.47)
			(stroke
				(width 0.05)
				(type default)
			)
			(fill no)
			(layer "B.CrtYd")
		)
		(fp_rect
			(start -0.5 0.25)
			(end 0.5 -0.25)
			(stroke
				(width 0.15)
				(type solid)
			)
			(fill no)
			(layer "B.Fab")
		)
		(fp_text user "Author: Antmicro"
			(at -0.95 -4.169 0)
			(layer "B.Fab")
			(effects
				(font
					(size 0.7 0.7)
					(thickness 0.15)
				)
				(justify left bottom mirror)
			)
		)
		(fp_text user "License: Apache-2.0"
			(at -0.95 -5.169 0)
			(layer "B.Fab")
			(effects
				(font
					(size 0.7 0.7)
					(thickness 0.15)
				)
				(justify left bottom mirror)
			)
		)
		(fp_text user "${REFERENCE}"
			(at -0.95 -3.168 0)
			(layer "B.Fab")
			(effects
				(font
					(size 0.7 0.7)
					(thickness 0.15)
				)
				(justify left bottom mirror)
			)
		)
		(pad "1" smd roundrect
			(at -0.48 0 180)
			(size 0.59 0.64)
			(layers "B.Cu" "B.Mask" "B.Paste")
			(roundrect_rratio 0.25)
			(net 57 "+3V3_TB")
			(pintype "passive")
		)
		(pad "2" smd roundrect
			(at 0.48 0 180)
			(size 0.59 0.64)
			(layers "B.Cu" "B.Mask" "B.Paste")
			(roundrect_rratio 0.25)
			(net 227 "Net-(U4D-TDO)")
			(pintype "passive")
		)
	)
	(footprint "antmicro-footprints:TP_SMD_0.75mm"
		(layer "B.Cu")
		(at 159.731865 62.935117 90)
		(property "Reference" "TP27"
			(at -0.264883 3.268135 180)
			(layer "B.SilkS")
			(effects
				(font
					(size 0.7 0.7)
					(thickness 0.15)
				)
				(justify left bottom mirror)
			)
		)
		(property "Value" "TP_0.75mm_SMD"
			(at 0 -1.2 270)
			(layer "B.Fab")
			(effects
				(font
					(size 0.7 0.7)
					(thickness 0.15)
				)
				(justify left bottom mirror)
			)
		)
		(property "Description" "SMT test point"
			(at 0 0 270)
			(layer "B.Fab")
			(hide yes)
			(effects
				(font
					(size 1.27 1.27)
					(thickness 0.15)
				)
				(justify mirror)
			)
		)
		(property "MPN" ""
			(at 0 0 90)
			(unlocked yes)
			(layer "B.Fab")
			(hide yes)
			(effects
				(font
					(size 1 1)
					(thickness 0.15)
				)
				(justify mirror)
			)
		)
		(property "Manufacturer" ""
			(at 0 0 90)
			(unlocked yes)
			(layer "B.Fab")
			(hide yes)
			(effects
				(font
					(size 1 1)
					(thickness 0.15)
				)
				(justify mirror)
			)
		)
		(property "Author" "Antmicro"
			(at 0 0 90)
			(unlocked yes)
			(layer "B.Fab")
			(hide yes)
			(effects
				(font
					(size 1 1)
					(thickness 0.15)
				)
				(justify mirror)
			)
		)
		(property "License" "Apache-2.0"
			(at 0 0 90)
			(unlocked yes)
			(layer "B.Fab")
			(hide yes)
			(effects
				(font
					(size 1 1)
					(thickness 0.15)
				)
				(justify mirror)
			)
		)
		(sheetname "/X710-AT2 Misc/")
		(sheetfile "x710-at2-mics.kicad_sch")
		(attr exclude_from_pos_files exclude_from_bom)
		(fp_circle
			(center 0 0)
			(end 0.475 0)
			(stroke
				(width 0.05)
				(type default)
			)
			(fill no)
			(layer "B.CrtYd")
		)
		(fp_text user "${REFERENCE}"
			(at -0.4 -2.7 270)
			(layer "B.Fab")
			(effects
				(font
					(size 0.7 0.7)
					(thickness 0.15)
				)
				(justify left bottom mirror)
			)
		)
		(fp_text user "Author: Antmicro"
			(at -0.4 -3.901 270)
			(layer "B.Fab")
			(effects
				(font
					(size 0.7 0.7)
					(thickness 0.15)
				)
				(justify left bottom mirror)
			)
		)
		(fp_text user "License: Apache-2.0"
			(at -0.4 -5.101 270)
			(layer "B.Fab")
			(effects
				(font
					(size 0.7 0.7)
					(thickness 0.15)
				)
				(justify left bottom mirror)
			)
		)
		(pad "1" smd circle
			(at 0 0 90)
			(size 0.75 0.75)
			(layers "B.Cu" "B.Mask")
			(net 139 "/X710-AT2 Misc/NCSI.RXD_0")
			(pinfunction "1")
			(pintype "passive")
		)
	)
)
